FILE_TYPE=LIBRARY_PARTS;
primitive 'ISL99390FRZTR5935';
  pin
    'PWM':
      PIN_NUMBER='(34)';
      INPUT_LOAD='(-0.01,0.01)';
    'REFIN':
      PIN_NUMBER='(39)';
      INPUT_LOAD='(-0.01,0.01)';
    'VCC':
      PIN_NUMBER='(3)';
      PINUSE='POWER';
      NO_LOAD_CHECK='Both';
      NO_IO_CHECK='Both';
      NO_ASSERT_CHECK='TRUE';
      NO_DIR_CHECK='TRUE';
      ALLOW_CONNECT='TRUE';
    'AGND':
      PIN_NUMBER='(2)';
      PINUSE='POWER';
      NO_LOAD_CHECK='Both';
      NO_IO_CHECK='Both';
      NO_ASSERT_CHECK='TRUE';
      NO_DIR_CHECK='TRUE';
      ALLOW_CONNECT='TRUE';
    'BOOT':
      PIN_NUMBER='(33)';
      PINUSE='POWER';
      NO_LOAD_CHECK='Both';
      NO_IO_CHECK='Both';
      NO_ASSERT_CHECK='TRUE';
      NO_DIR_CHECK='TRUE';
      ALLOW_CONNECT='TRUE';
    'VIN1':
      PIN_NUMBER='(25_29)';
      INPUT_LOAD='(-0.01,0.01)';
    'PHASE':
      PIN_NUMBER='(32)';
      PINUSE='POWER';
      NO_LOAD_CHECK='Both';
      NO_IO_CHECK='Both';
      NO_ASSERT_CHECK='TRUE';
      NO_DIR_CHECK='TRUE';
      ALLOW_CONNECT='TRUE';
    'PVCC':
      PIN_NUMBER='(4)';
      PINUSE='POWER';
      NO_LOAD_CHECK='Both';
      NO_IO_CHECK='Both';
      NO_ASSERT_CHECK='TRUE';
      NO_DIR_CHECK='TRUE';
      ALLOW_CONNECT='TRUE';
    'TOUT_FLT':
      PIN_NUMBER='(36)';
      OUTPUT_LOAD='(1.0,-1.0)';
    'IOUT':
      PIN_NUMBER='(38)';
      OUTPUT_LOAD='(1.0,-1.0)';
    'LSET':
      PIN_NUMBER='(37)';
      OUTPUT_LOAD='(1.0,-1.0)';
    'SW':
      PIN_NUMBER='(10_19)';
      OUTPUT_LOAD='(1.0,-1.0)';
    'PGND1':
      PIN_NUMBER='(5)';
      PINUSE='POWER';
      NO_LOAD_CHECK='Both';
      NO_IO_CHECK='Both';
      NO_ASSERT_CHECK='TRUE';
      NO_DIR_CHECK='TRUE';
      ALLOW_CONNECT='TRUE';
    'VIN2':
      PIN_NUMBER='(30)';
      INPUT_LOAD='(-0.01,0.01)';
    'VOS':
      PIN_NUMBER='(1)';
      INPUT_LOAD='(-0.01,0.01)';
    'PGND3':
      PIN_NUMBER='(40)';
      PINUSE='POWER';
      NO_LOAD_CHECK='Both';
      NO_IO_CHECK='Both';
      NO_ASSERT_CHECK='TRUE';
      NO_DIR_CHECK='TRUE';
      ALLOW_CONNECT='TRUE';
    'EN':
      PIN_NUMBER='(35)';
      INPUT_LOAD='(-0.01,0.01)';
    'DNC':
      PIN_NUMBER='(31)';
      OUTPUT_TYPE='(TS,TS)';
      INPUT_LOAD='(-0.01,0.01)';
      OUTPUT_LOAD='(1.0,-1.0)';
    'GL1':
      PIN_NUMBER='(6)';
      OUTPUT_LOAD='(1.0,-1.0)';
    'GL2':
      PIN_NUMBER='(41)';
      OUTPUT_LOAD='(1.0,-1.0)';
    'PGND2':
      PIN_NUMBER='(7_9-20_24)';
      PINUSE='POWER';
      NO_LOAD_CHECK='Both';
      NO_IO_CHECK='Both';
      NO_ASSERT_CHECK='TRUE';
      NO_DIR_CHECK='TRUE';
      ALLOW_CONNECT='TRUE';
  end_pin;
  body
    PART_NAME='ISL99390FRZTR5935';
    BODY_NAME='ISL99390FRZTR5935';
    PHYS_DES_PREFIX='U';
    CLASS='IC';
  end_body;
end_primitive;

END.
